(kicad_pcb
	(version 20241229)
	(generator "pcbnew")
	(generator_version "9.0")
	(general
		(thickness 1.6296)
		(legacy_teardrops no)
	)
	(paper "A3")
	(title_block
		(title "Thunderbolt to 10GbE adapter")
		(date "2026-04-21")
		(rev "1.1.0")
		(company "Antmicro Ltd")
		(comment 1 "www.antmicro.com")
		(comment 9 "footprints 536-540 of 703")
	)
	(layers
		(0 "F.Cu" signal)
		(4 "In1.Cu" signal)
		(6 "In2.Cu" signal)
		(8 "In3.Cu" signal)
		(10 "In4.Cu" signal)
		(12 "In5.Cu" signal)
		(14 "In6.Cu" signal)
		(2 "B.Cu" signal)
		(9 "F.Adhes" user "F.Adhesive")
		(11 "B.Adhes" user "B.Adhesive")
		(13 "F.Paste" user)
		(15 "B.Paste" user)
		(5 "F.SilkS" user "F.Silkscreen")
		(7 "B.SilkS" user "B.Silkscreen")
		(1 "F.Mask" user)
		(3 "B.Mask" user)
		(17 "Dwgs.User" user "User.Drawings")
		(19 "Cmts.User" user "User.Comments")
		(21 "Eco1.User" user "User.Eco1")
		(23 "Eco2.User" user "User.Eco2")
		(25 "Edge.Cuts" user)
		(27 "Margin" user)
		(31 "F.CrtYd" user "F.Courtyard")
		(29 "B.CrtYd" user "B.Courtyard")
		(35 "F.Fab" user)
		(33 "B.Fab" user)
	)
	(footprint "antmicro-footprints:C_0402_1005Metric"
		(layer "B.Cu")
		(at 158.451866 87.415117 -90)
		(descr "Capacitor SMD 0402")
		(tags "capacitor SMD 0402")
		(property "Reference" "C168"
			(at 9.984883 -20.453133 90)
			(layer "B.SilkS")
			(effects
				(font
					(size 0.7 0.7)
					(thickness 0.15)
				)
				(justify mirror)
			)
		)
		(property "Value" "C_1u_25V_0402"
			(at -1.022927 -2.155213 90)
			(layer "B.Fab")
			(effects
				(font
					(size 0.7 0.7)
					(thickness 0.15)
				)
				(justify left bottom mirror)
			)
		)
		(property "Datasheet" "https://www.murata.com/products/productdetail?partno=GRM155R61E105KE11%23"
			(at 0 0 90)
			(layer "B.Fab")
			(hide yes)
			(effects
				(font
					(size 1.27 1.27)
					(thickness 0.15)
				)
				(justify mirror)
			)
		)
		(property "Description" "SMD Multilayer Ceramic Capacitor, 1 µF, 25 V, 0402 [1005 Metric], ± 10%, X5R, GRM Series"
			(at 0 0 90)
			(layer "B.Fab")
			(hide yes)
			(effects
				(font
					(size 1.27 1.27)
					(thickness 0.15)
				)
				(justify mirror)
			)
		)
		(property "MPN" "GRM155R61E105KE11J"
			(at 0 0 270)
			(unlocked yes)
			(layer "B.Fab")
			(hide yes)
			(effects
				(font
					(size 1 1)
					(thickness 0.15)
				)
				(justify mirror)
			)
		)
		(property "Manufacturer" "Murata"
			(at 0 0 270)
			(unlocked yes)
			(layer "B.Fab")
			(hide yes)
			(effects
				(font
					(size 1 1)
					(thickness 0.15)
				)
				(justify mirror)
			)
		)
		(property "License" "Apache-2.0"
			(at 0 0 270)
			(unlocked yes)
			(layer "B.Fab")
			(hide yes)
			(effects
				(font
					(size 1 1)
					(thickness 0.15)
				)
				(justify mirror)
			)
		)
		(property "Author" "Antmicro"
			(at 0 0 270)
			(unlocked yes)
			(layer "B.Fab")
			(hide yes)
			(effects
				(font
					(size 1 1)
					(thickness 0.15)
				)
				(justify mirror)
			)
		)
		(property "Val" "1u"
			(at 0 0 270)
			(unlocked yes)
			(layer "B.Fab")
			(hide yes)
			(effects
				(font
					(size 1 1)
					(thickness 0.15)
				)
				(justify mirror)
			)
		)
		(property "Voltage" "25V"
			(at 0 0 270)
			(unlocked yes)
			(layer "B.Fab")
			(hide yes)
			(effects
				(font
					(size 1 1)
					(thickness 0.15)
				)
				(justify mirror)
			)
		)
		(property "Dielectric" "X5R"
			(at 0 0 270)
			(unlocked yes)
			(layer "B.Fab")
			(hide yes)
			(effects
				(font
					(size 1 1)
					(thickness 0.15)
				)
				(justify mirror)
			)
		)
		(sheetname "/X710-AT2 power/")
		(sheetfile "x710-at2-power.kicad_sch")
		(attr smd)
		(fp_rect
			(start -0.925 0.47)
			(end 0.925 -0.47)
			(stroke
				(width 0.05)
				(type default)
			)
			(fill no)
			(layer "B.CrtYd")
		)
		(fp_line
			(start -0.494 0.25)
			(end 0.504 0.25)
			(stroke
				(width 0.15)
				(type solid)
			)
			(layer "B.Fab")
		)
		(fp_line
			(start 0.504 0.25)
			(end 0.504 -0.248)
			(stroke
				(width 0.15)
				(type solid)
			)
			(layer "B.Fab")
		)
		(fp_line
			(start -0.494 -0.248)
			(end -0.494 0.25)
			(stroke
				(width 0.15)
				(type solid)
			)
			(layer "B.Fab")
		)
		(fp_line
			(start 0.504 -0.248)
			(end -0.494 -0.248)
			(stroke
				(width 0.15)
				(type solid)
			)
			(layer "B.Fab")
		)
		(fp_text user "Author: Antmicro"
			(at -0.939 -3.399 90)
			(layer "B.Fab")
			(effects
				(font
					(size 0.7 0.7)
					(thickness 0.15)
				)
				(justify left bottom mirror)
			)
		)
		(fp_text user "${REFERENCE}"
			(at -0.939 -4.599 90)
			(layer "B.Fab")
			(effects
				(font
					(size 0.7 0.7)
					(thickness 0.15)
				)
				(justify left bottom mirror)
			)
		)
		(fp_text user "License: Apache-2.0"
			(at -0.939 -5.799 90)
			(layer "B.Fab")
			(effects
				(font
					(size 0.7 0.7)
					(thickness 0.15)
				)
				(justify left bottom mirror)
			)
		)
		(pad "1" smd roundrect
			(at -0.48 0 270)
			(size 0.59 0.64)
			(layers "B.Cu" "B.Mask" "B.Paste")
			(roundrect_rratio 0.25)
			(net 23 "GND")
			(pintype "passive")
		)
		(pad "2" smd roundrect
			(at 0.48 0 270)
			(size 0.59 0.64)
			(layers "B.Cu" "B.Mask" "B.Paste")
			(roundrect_rratio 0.25)
			(net 20 "XGB_AVDDH")
			(pintype "passive")
		)
	)
	(footprint "antmicro-footprints:C_0402_1005Metric"
		(layer "B.Cu")
		(at 153.031867 78.260117 180)
		(descr "Capacitor SMD 0402")
		(tags "capacitor SMD 0402")
		(property "Reference" "C222"
			(at -21.168135 -9.464883 0)
			(layer "B.SilkS")
			(effects
				(font
					(size 0.7 0.7)
					(thickness 0.15)
				)
				(justify mirror)
			)
		)
		(property "Value" "C_1u_25V_0402"
			(at -1.022927 -2.155213 0)
			(layer "B.Fab")
			(effects
				(font
					(size 0.7 0.7)
					(thickness 0.15)
				)
				(justify left bottom mirror)
			)
		)
		(property "Datasheet" "https://www.murata.com/products/productdetail?partno=GRM155R61E105KE11%23"
			(at 0 0 0)
			(layer "B.Fab")
			(hide yes)
			(effects
				(font
					(size 1.27 1.27)
					(thickness 0.15)
				)
				(justify mirror)
			)
		)
		(property "Description" "SMD Multilayer Ceramic Capacitor, 1 µF, 25 V, 0402 [1005 Metric], ± 10%, X5R, GRM Series"
			(at 0 0 0)
			(layer "B.Fab")
			(hide yes)
			(effects
				(font
					(size 1.27 1.27)
					(thickness 0.15)
				)
				(justify mirror)
			)
		)
		(property "MPN" "GRM155R61E105KE11J"
			(at 0 0 180)
			(unlocked yes)
			(layer "B.Fab")
			(hide yes)
			(effects
				(font
					(size 1 1)
					(thickness 0.15)
				)
				(justify mirror)
			)
		)
		(property "Manufacturer" "Murata"
			(at 0 0 180)
			(unlocked yes)
			(layer "B.Fab")
			(hide yes)
			(effects
				(font
					(size 1 1)
					(thickness 0.15)
				)
				(justify mirror)
			)
		)
		(property "License" "Apache-2.0"
			(at 0 0 180)
			(unlocked yes)
			(layer "B.Fab")
			(hide yes)
			(effects
				(font
					(size 1 1)
					(thickness 0.15)
				)
				(justify mirror)
			)
		)
		(property "Author" "Antmicro"
			(at 0 0 180)
			(unlocked yes)
			(layer "B.Fab")
			(hide yes)
			(effects
				(font
					(size 1 1)
					(thickness 0.15)
				)
				(justify mirror)
			)
		)
		(property "Val" "1u"
			(at 0 0 180)
			(unlocked yes)
			(layer "B.Fab")
			(hide yes)
			(effects
				(font
					(size 1 1)
					(thickness 0.15)
				)
				(justify mirror)
			)
		)
		(property "Voltage" "25V"
			(at 0 0 180)
			(unlocked yes)
			(layer "B.Fab")
			(hide yes)
			(effects
				(font
					(size 1 1)
					(thickness 0.15)
				)
				(justify mirror)
			)
		)
		(property "Dielectric" "X5R"
			(at 0 0 180)
			(unlocked yes)
			(layer "B.Fab")
			(hide yes)
			(effects
				(font
					(size 1 1)
					(thickness 0.15)
				)
				(justify mirror)
			)
		)
		(sheetname "/X710-AT2 power/")
		(sheetfile "x710-at2-power.kicad_sch")
		(attr smd)
		(fp_rect
			(start -0.925 0.47)
			(end 0.925 -0.47)
			(stroke
				(width 0.05)
				(type default)
			)
			(fill no)
			(layer "B.CrtYd")
		)
		(fp_line
			(start 0.504 0.25)
			(end 0.504 -0.248)
			(stroke
				(width 0.15)
				(type solid)
			)
			(layer "B.Fab")
		)
		(fp_line
			(start 0.504 -0.248)
			(end -0.494 -0.248)
			(stroke
				(width 0.15)
				(type solid)
			)
			(layer "B.Fab")
		)
		(fp_line
			(start -0.494 0.25)
			(end 0.504 0.25)
			(stroke
				(width 0.15)
				(type solid)
			)
			(layer "B.Fab")
		)
		(fp_line
			(start -0.494 -0.248)
			(end -0.494 0.25)
			(stroke
				(width 0.15)
				(type solid)
			)
			(layer "B.Fab")
		)
		(fp_text user "${REFERENCE}"
			(at -0.939 -4.599 0)
			(layer "B.Fab")
			(effects
				(font
					(size 0.7 0.7)
					(thickness 0.15)
				)
				(justify left bottom mirror)
			)
		)
		(fp_text user "License: Apache-2.0"
			(at -0.939 -5.799 0)
			(layer "B.Fab")
			(effects
				(font
					(size 0.7 0.7)
					(thickness 0.15)
				)
				(justify left bottom mirror)
			)
		)
		(fp_text user "Author: Antmicro"
			(at -0.939 -3.399 0)
			(layer "B.Fab")
			(effects
				(font
					(size 0.7 0.7)
					(thickness 0.15)
				)
				(justify left bottom mirror)
			)
		)
		(pad "1" smd roundrect
			(at -0.48 0 180)
			(size 0.59 0.64)
			(layers "B.Cu" "B.Mask" "B.Paste")
			(roundrect_rratio 0.25)
			(net 23 "GND")
			(pintype "passive")
		)
		(pad "2" smd roundrect
			(at 0.48 0 180)
			(size 0.59 0.64)
			(layers "B.Cu" "B.Mask" "B.Paste")
			(roundrect_rratio 0.25)
			(net 1 "VCCA")
			(pintype "passive")
		)
	)
	(footprint "antmicro-footprints:C_0402_1005Metric"
		(layer "B.Cu")
		(at 158.926866 82.110117)
		(descr "Capacitor SMD 0402")
		(tags "capacitor SMD 0402")
		(property "Reference" "C200"
			(at 19.873134 9.464883 180)
			(layer "B.SilkS")
			(effects
				(font
					(size 0.7 0.7)
					(thickness 0.15)
				)
				(justify mirror)
			)
		)
		(property "Value" "C_1u_25V_0402"
			(at -1.022927 -2.155213 180)
			(layer "B.Fab")
			(effects
				(font
					(size 0.7 0.7)
					(thickness 0.15)
				)
				(justify left bottom mirror)
			)
		)
		(property "Datasheet" "https://www.murata.com/products/productdetail?partno=GRM155R61E105KE11%23"
			(at 0 0 180)
			(layer "B.Fab")
			(hide yes)
			(effects
				(font
					(size 1.27 1.27)
					(thickness 0.15)
				)
				(justify mirror)
			)
		)
		(property "Description" "SMD Multilayer Ceramic Capacitor, 1 µF, 25 V, 0402 [1005 Metric], ± 10%, X5R, GRM Series"
			(at 0 0 180)
			(layer "B.Fab")
			(hide yes)
			(effects
				(font
					(size 1.27 1.27)
					(thickness 0.15)
				)
				(justify mirror)
			)
		)
		(property "MPN" "GRM155R61E105KE11J"
			(at 0 0 0)
			(unlocked yes)
			(layer "B.Fab")
			(hide yes)
			(effects
				(font
					(size 1 1)
					(thickness 0.15)
				)
				(justify mirror)
			)
		)
		(property "Manufacturer" "Murata"
			(at 0 0 0)
			(unlocked yes)
			(layer "B.Fab")
			(hide yes)
			(effects
				(font
					(size 1 1)
					(thickness 0.15)
				)
				(justify mirror)
			)
		)
		(property "License" "Apache-2.0"
			(at 0 0 0)
			(unlocked yes)
			(layer "B.Fab")
			(hide yes)
			(effects
				(font
					(size 1 1)
					(thickness 0.15)
				)
				(justify mirror)
			)
		)
		(property "Author" "Antmicro"
			(at 0 0 0)
			(unlocked yes)
			(layer "B.Fab")
			(hide yes)
			(effects
				(font
					(size 1 1)
					(thickness 0.15)
				)
				(justify mirror)
			)
		)
		(property "Val" "1u"
			(at 0 0 0)
			(unlocked yes)
			(layer "B.Fab")
			(hide yes)
			(effects
				(font
					(size 1 1)
					(thickness 0.15)
				)
				(justify mirror)
			)
		)
		(property "Voltage" "25V"
			(at 0 0 0)
			(unlocked yes)
			(layer "B.Fab")
			(hide yes)
			(effects
				(font
					(size 1 1)
					(thickness 0.15)
				)
				(justify mirror)
			)
		)
		(property "Dielectric" "X5R"
			(at 0 0 0)
			(unlocked yes)
			(layer "B.Fab")
			(hide yes)
			(effects
				(font
					(size 1 1)
					(thickness 0.15)
				)
				(justify mirror)
			)
		)
		(sheetname "/X710-AT2 power/")
		(sheetfile "x710-at2-power.kicad_sch")
		(attr smd)
		(fp_rect
			(start -0.925 0.47)
			(end 0.925 -0.47)
			(stroke
				(width 0.05)
				(type default)
			)
			(fill no)
			(layer "B.CrtYd")
		)
		(fp_line
			(start -0.494 -0.248)
			(end -0.494 0.25)
			(stroke
				(width 0.15)
				(type solid)
			)
			(layer "B.Fab")
		)
		(fp_line
			(start -0.494 0.25)
			(end 0.504 0.25)
			(stroke
				(width 0.15)
				(type solid)
			)
			(layer "B.Fab")
		)
		(fp_line
			(start 0.504 -0.248)
			(end -0.494 -0.248)
			(stroke
				(width 0.15)
				(type solid)
			)
			(layer "B.Fab")
		)
		(fp_line
			(start 0.504 0.25)
			(end 0.504 -0.248)
			(stroke
				(width 0.15)
				(type solid)
			)
			(layer "B.Fab")
		)
		(fp_text user "License: Apache-2.0"
			(at -0.939 -5.799 180)
			(layer "B.Fab")
			(effects
				(font
					(size 0.7 0.7)
					(thickness 0.15)
				)
				(justify left bottom mirror)
			)
		)
		(fp_text user "Author: Antmicro"
			(at -0.939 -3.399 180)
			(layer "B.Fab")
			(effects
				(font
					(size 0.7 0.7)
					(thickness 0.15)
				)
				(justify left bottom mirror)
			)
		)
		(fp_text user "${REFERENCE}"
			(at -0.939 -4.599 180)
			(layer "B.Fab")
			(effects
				(font
					(size 0.7 0.7)
					(thickness 0.15)
				)
				(justify left bottom mirror)
			)
		)
		(pad "1" smd roundrect
			(at -0.48 0)
			(size 0.59 0.64)
			(layers "B.Cu" "B.Mask" "B.Paste")
			(roundrect_rratio 0.25)
			(net 23 "GND")
			(pintype "passive")
		)
		(pad "2" smd roundrect
			(at 0.48 0)
			(size 0.59 0.64)
			(layers "B.Cu" "B.Mask" "B.Paste")
			(roundrect_rratio 0.25)
			(net 14 "P1_AVDDL")
			(pintype "passive")
		)
	)
	(footprint "antmicro-footprints:R_0402_1005Metric"
		(layer "B.Cu")
		(at 145.631866 82.260117 180)
		(descr "Resistor SMD 0402")
		(tags "resistor SMD 0402")
		(property "Reference" "R122"
			(at -17.768134 -9.464883 0)
			(layer "B.SilkS")
			(effects
				(font
					(size 0.7 0.7)
					(thickness 0.15)
				)
				(justify mirror)
			)
		)
		(property "Value" "R_100R_0402"
			(at -1.011843 -1.772047 0)
			(layer "B.Fab")
			(effects
				(font
					(size 0.7 0.7)
					(thickness 0.15)
				)
				(justify left bottom mirror)
			)
		)
		(property "Datasheet" "https://www.bourns.com/docs/product-datasheets/cr.pdf"
			(at 0 0 0)
			(layer "B.Fab")
			(hide yes)
			(effects
				(font
					(size 1.27 1.27)
					(thickness 0.15)
				)
				(justify mirror)
			)
		)
		(property "Description" "SMD Chip Resistor, 100 ohm, ± 1%, 62.5 mW, 0402 [1005 Metric], Thick Film, General Purpose"
			(at 0 0 0)
			(layer "B.Fab")
			(hide yes)
			(effects
				(font
					(size 1.27 1.27)
					(thickness 0.15)
				)
				(justify mirror)
			)
		)
		(property "MPN" "CR0402-FX-1000GLF"
			(at 0 0 180)
			(unlocked yes)
			(layer "B.Fab")
			(hide yes)
			(effects
				(font
					(size 1 1)
					(thickness 0.15)
				)
				(justify mirror)
			)
		)
		(property "Manufacturer" "Bourns"
			(at 0 0 180)
			(unlocked yes)
			(layer "B.Fab")
			(hide yes)
			(effects
				(font
					(size 1 1)
					(thickness 0.15)
				)
				(justify mirror)
			)
		)
		(property "License" "Apache-2.0"
			(at 0 0 180)
			(unlocked yes)
			(layer "B.Fab")
			(hide yes)
			(effects
				(font
					(size 1 1)
					(thickness 0.15)
				)
				(justify mirror)
			)
		)
		(property "Author" "Antmicro"
			(at 0 0 180)
			(unlocked yes)
			(layer "B.Fab")
			(hide yes)
			(effects
				(font
					(size 1 1)
					(thickness 0.15)
				)
				(justify mirror)
			)
		)
		(property "Val" "100R"
			(at 0 0 180)
			(unlocked yes)
			(layer "B.Fab")
			(hide yes)
			(effects
				(font
					(size 1 1)
					(thickness 0.15)
				)
				(justify mirror)
			)
		)
		(property "Tolerance" "1%"
			(at 0 0 180)
			(unlocked yes)
			(layer "B.Fab")
			(hide yes)
			(effects
				(font
					(size 1 1)
					(thickness 0.15)
				)
				(justify mirror)
			)
		)
		(sheetname "/X710-AT2 RSVD/")
		(sheetfile "x710-at2-rsvd.kicad_sch")
		(attr smd)
		(fp_rect
			(start -0.925 0.47)
			(end 0.925 -0.47)
			(stroke
				(width 0.05)
				(type default)
			)
			(fill no)
			(layer "B.CrtYd")
		)
		(fp_rect
			(start -0.5 0.25)
			(end 0.5 -0.25)
			(stroke
				(width 0.15)
				(type solid)
			)
			(fill no)
			(layer "B.Fab")
		)
		(fp_text user "Author: Antmicro"
			(at -0.95 -4.169 0)
			(layer "B.Fab")
			(effects
				(font
					(size 0.7 0.7)
					(thickness 0.15)
				)
				(justify left bottom mirror)
			)
		)
		(fp_text user "License: Apache-2.0"
			(at -0.95 -5.169 0)
			(layer "B.Fab")
			(effects
				(font
					(size 0.7 0.7)
					(thickness 0.15)
				)
				(justify left bottom mirror)
			)
		)
		(fp_text user "${REFERENCE}"
			(at -0.95 -3.168 0)
			(layer "B.Fab")
			(effects
				(font
					(size 0.7 0.7)
					(thickness 0.15)
				)
				(justify left bottom mirror)
			)
		)
		(pad "1" smd roundrect
			(at -0.48 0 180)
			(size 0.59 0.64)
			(layers "B.Cu" "B.Mask" "B.Paste")
			(roundrect_rratio 0.25)
			(net 23 "GND")
			(pintype "passive")
		)
		(pad "2" smd roundrect
			(at 0.48 0 180)
			(size 0.59 0.64)
			(layers "B.Cu" "B.Mask" "B.Paste")
			(roundrect_rratio 0.25)
			(net 93 "/X710-AT2 RSVD/RSVDY22_VSS")
			(pintype "passive")
		)
	)
	(footprint "antmicro-footprints:R_0402_1005Metric"
		(layer "B.Cu")
		(at 162.381866 74.485117)
		(descr "Resistor SMD 0402")
		(tags "resistor SMD 0402")
		(property "Reference" "R197"
			(at 2.368134 0.014883 180)
			(layer "B.SilkS")
			(effects
				(font
					(size 0.7 0.7)
					(thickness 0.15)
				)
				(justify mirror)
			)
		)
		(property "Value" "R_0R_0402"
			(at -1.011843 -1.772047 180)
			(layer "B.Fab")
			(effects
				(font
					(size 0.7 0.7)
					(thickness 0.15)
				)
				(justify left bottom mirror)
			)
		)
		(property "Datasheet" "https://industrial.panasonic.com/cdbs/www-data/pdf/RDA0000/AOA0000C301.pdf"
			(at 0 0 180)
			(layer "B.Fab")
			(hide yes)
			(effects
				(font
					(size 1.27 1.27)
					(thickness 0.15)
				)
				(justify mirror)
			)
		)
		(property "Description" "SMD Chip Resistor, Jumper, 0 ohm, 100 mW, 0402 [1005 Metric], Thick Film, General Purpose"
			(at 0 0 180)
			(layer "B.Fab")
			(hide yes)
			(effects
				(font
					(size 1.27 1.27)
					(thickness 0.15)
				)
				(justify mirror)
			)
		)
		(property "MPN" "ERJ2GE0R00X"
			(at 0 0 0)
			(unlocked yes)
			(layer "B.Fab")
			(hide yes)
			(effects
				(font
					(size 1 1)
					(thickness 0.15)
				)
				(justify mirror)
			)
		)
		(property "Manufacturer" "Panasonic"
			(at 0 0 0)
			(unlocked yes)
			(layer "B.Fab")
			(hide yes)
			(effects
				(font
					(size 1 1)
					(thickness 0.15)
				)
				(justify mirror)
			)
		)
		(property "License" "Apache-2.0"
			(at 0 0 0)
			(unlocked yes)
			(layer "B.Fab")
			(hide yes)
			(effects
				(font
					(size 1 1)
					(thickness 0.15)
				)
				(justify mirror)
			)
		)
		(property "Author" "Antmicro"
			(at 0 0 0)
			(unlocked yes)
			(layer "B.Fab")
			(hide yes)
			(effects
				(font
					(size 1 1)
					(thickness 0.15)
				)
				(justify mirror)
			)
		)
		(property "Val" "0R"
			(at 0 0 0)
			(unlocked yes)
			(layer "B.Fab")
			(hide yes)
			(effects
				(font
					(size 1 1)
					(thickness 0.15)
				)
				(justify mirror)
			)
		)
		(property "Tolerance" "~"
			(at 0 0 0)
			(unlocked yes)
			(layer "B.Fab")
			(hide yes)
			(effects
				(font
					(size 1 1)
					(thickness 0.15)
				)
				(justify mirror)
			)
		)
		(property "Current" "1A"
			(at 0 0 0)
			(unlocked yes)
			(layer "B.Fab")
			(hide yes)
			(effects
				(font
					(size 1 1)
					(thickness 0.15)
				)
				(justify mirror)
			)
		)
		(sheetname "/X710-AT2 10GbE/")
		(sheetfile "x710-at2-10gbe.kicad_sch")
		(attr smd)
		(fp_rect
			(start -0.925 0.47)
			(end 0.925 -0.47)
			(stroke
				(width 0.05)
				(type default)
			)
			(fill no)
			(layer "B.CrtYd")
		)
		(fp_rect
			(start -0.5 0.25)
			(end 0.5 -0.25)
			(stroke
				(width 0.15)
				(type solid)
			)
			(fill no)
			(layer "B.Fab")
		)
		(fp_text user "${REFERENCE}"
			(at -0.95 -3.168 180)
			(layer "B.Fab")
			(effects
				(font
					(size 0.7 0.7)
					(thickness 0.15)
				)
				(justify left bottom mirror)
			)
		)
		(fp_text user "License: Apache-2.0"
			(at -0.95 -5.169 180)
			(layer "B.Fab")
			(effects
				(font
					(size 0.7 0.7)
					(thickness 0.15)
				)
				(justify left bottom mirror)
			)
		)
		(fp_text user "Author: Antmicro"
			(at -0.95 -4.169 180)
			(layer "B.Fab")
			(effects
				(font
					(size 0.7 0.7)
					(thickness 0.15)
				)
				(justify left bottom mirror)
			)
		)
		(pad "1" smd roundrect
			(at -0.48 0)
			(size 0.59 0.64)
			(layers "B.Cu" "B.Mask" "B.Paste")
			(roundrect_rratio 0.25)
			(net 111 "/X710-AT2 10GbE/~{P0_INT}")
			(pintype "passive")
		)
		(pad "2" smd roundrect
			(at 0.48 0)
			(size 0.59 0.64)
			(layers "B.Cu" "B.Mask" "B.Paste")
			(roundrect_rratio 0.25)
			(net 121 "/X710-AT2 10GbE/~{P0_INT_R}")
			(pintype "passive")
		)
	)
)
